# T6G (Grand Teton) — schematic netlist excerpt (pin names and nets, part order shuffled) for the footprints in the layout excerpt that follows; sources: Cadence DE-HDL packaged netlist, KiCad conversion of 04192023_DAF0TMB3IC0_F0TG_MB_C_brd_V02_OCP.brd

R1036  Q_RES  0 5% CHIP  pkg 0402LF  page 85 : A = FM_SMB_RST_E1S_0_N ; B = FM_SMB_RST_E1S_0_R_N

X4  TP_TDR_4P_FTS  TP_TDR_4P_DIP EMPTY  pkg TH  page 260
  S1  = TDR_DIFF_80_IN3_DP
  P1  = T1_GND
  P2  = T1_GND
  S2  = TDR_DIFF_80_IN3_DN

(kicad_pcb
	(version 20260206)
	(generator "pcbnew")
	(generator_version "10.0")
	(general
		(thickness 1.6)
		(legacy_teardrops no)
	)
	(paper "A4")
	(title_block
		(title "04192023_DAF0TMB3IC0_F0TG_MB_C_brd_V02_OCP.brd")
		(comment 1 "Grand Teton / footprints 3698-3699 of 8354")
	)
	(layers
		(0 "F.Cu" signal "TOP")
		(4 "In1.Cu" signal "GND")
		(6 "In2.Cu" signal "IN1")
		(8 "In3.Cu" signal "GND1")
		(10 "In4.Cu" signal "IN2")
		(12 "In5.Cu" signal "GND2")
		(14 "In6.Cu" signal "IN3")
		(16 "In7.Cu" signal "GND3")
		(18 "In8.Cu" signal "VCC")
		(20 "In9.Cu" signal "VCC1")
		(22 "In10.Cu" signal "GND4")
		(24 "In11.Cu" signal "IN4")
		(26 "In12.Cu" signal "GND5")
		(28 "In13.Cu" signal "IN5")
		(30 "In14.Cu" signal "GND6")
		(32 "In15.Cu" signal "IN6")
		(34 "In16.Cu" signal "GND7")
		(2 "B.Cu" signal "BOTTOM")
		(9 "F.Adhes" user "F.Adhesive")
		(11 "B.Adhes" user "B.Adhesive")
		(13 "F.Paste" user "Package Geometry/Pastemask Top")
		(15 "B.Paste" user "Package Geometry/Pastemask Bottom")
		(5 "F.SilkS" user "Ref Des/Silkscreen Top")
		(7 "B.SilkS" user "Ref Des/Silkscreen Bottom")
		(1 "F.Mask" user "Board Geometry/Soldermask Top")
		(3 "B.Mask" user "Board Geometry/Soldermask Bottom")
		(17 "Dwgs.User" user "User.Drawings")
		(19 "Cmts.User" user "User.Comments")
		(21 "Eco1.User" user "User.Eco1")
		(23 "Eco2.User" user "User.Eco2")
		(25 "Edge.Cuts" user "Board Geometry/Outline")
		(27 "Margin" user)
		(31 "F.CrtYd" user "Package Geometry/Place Bound Top")
		(29 "B.CrtYd" user "Package Geometry/Place Bound Bottom")
		(35 "F.Fab" user "Ref Des/Assembly Top")
		(33 "B.Fab" user "Ref Des/Assembly Bottom")
	)
	(footprint ""
		(layer "F.Cu")
		(at 187.833 -96.103948 -90)
		(property "Reference" "R1036"
			(at 0 0 270)
			(layer "F.SilkS")
			(hide yes)
			(effects
				(font
					(size 1.27 1.27)
				)
			)
		)
		(property "Value" ""
			(at 0 0 270)
			(layer "F.Fab")
			(effects
				(font
					(size 1.27 1.27)
				)
			)
		)
		(duplicate_pad_numbers_are_jumpers no)
		(fp_line
			(start -0.7874 0.4064)
			(end -0.7874 -0.4064)
			(stroke
				(width 0.1524)
				(type default)
			)
			(layer "F.SilkS")
		)
		(fp_line
			(start 0.7874 0.4064)
			(end -0.7874 0.4064)
			(stroke
				(width 0.1524)
				(type default)
			)
			(layer "F.SilkS")
		)
		(fp_line
			(start -0.7874 -0.4064)
			(end 0.7874 -0.4064)
			(stroke
				(width 0.1524)
				(type default)
			)
			(layer "F.SilkS")
		)
		(fp_line
			(start 0.7874 -0.4064)
			(end 0.7874 0.4064)
			(stroke
				(width 0.1524)
				(type default)
			)
			(layer "F.SilkS")
		)
		(fp_line
			(start -0.67945 0.3048)
			(end -0.67945 -0.305054)
			(stroke
				(width 0.1)
				(type default)
			)
			(layer "F.Fab")
		)
		(fp_line
			(start -0.12065 0.3048)
			(end -0.67945 0.3048)
			(stroke
				(width 0.1)
				(type default)
			)
			(layer "F.Fab")
		)
		(fp_line
			(start 0.120396 0.3048)
			(end 0.120396 0.2794)
			(stroke
				(width 0.1)
				(type default)
			)
			(layer "F.Fab")
		)
		(fp_line
			(start 0.67945 0.3048)
			(end 0.120396 0.3048)
			(stroke
				(width 0.1)
				(type default)
			)
			(layer "F.Fab")
		)
		(fp_line
			(start -0.12065 0.2794)
			(end -0.12065 0.3048)
			(stroke
				(width 0.1)
				(type default)
			)
			(layer "F.Fab")
		)
		(fp_line
			(start 0.120396 0.2794)
			(end -0.12065 0.2794)
			(stroke
				(width 0.1)
				(type default)
			)
			(layer "F.Fab")
		)
		(fp_line
			(start -0.12065 -0.2794)
			(end 0.12065 -0.2794)
			(stroke
				(width 0.1)
				(type default)
			)
			(layer "F.Fab")
		)
		(fp_line
			(start 0.12065 -0.2794)
			(end 0.12065 -0.3048)
			(stroke
				(width 0.1)
				(type default)
			)
			(layer "F.Fab")
		)
		(fp_line
			(start 0.12065 -0.3048)
			(end 0.67945 -0.3048)
			(stroke
				(width 0.1)
				(type default)
			)
			(layer "F.Fab")
		)
		(fp_line
			(start 0.67945 -0.3048)
			(end 0.67945 0.3048)
			(stroke
				(width 0.1)
				(type default)
			)
			(layer "F.Fab")
		)
		(fp_line
			(start -0.67945 -0.305054)
			(end -0.12065 -0.305054)
			(stroke
				(width 0.1)
				(type default)
			)
			(layer "F.Fab")
		)
		(fp_line
			(start -0.12065 -0.305054)
			(end -0.12065 -0.2794)
			(stroke
				(width 0.1)
				(type default)
			)
			(layer "F.Fab")
		)
		(pad "1" smd circle
			(at -0.40005 0 270)
			(size 0 0)
			(layers "F.Cu" "F.Mask" "F.Paste")
			(net "FM_SMB_RST_E1S_0_N")
		)
		(pad "2" smd circle
			(at 0.40005 0 270)
			(size 0 0)
			(layers "F.Cu" "F.Mask" "F.Paste")
			(net "FM_SMB_RST_E1S_0_R_N")
		)
	)
	(footprint ""
		(layer "F.Cu")
		(at 495.90833 -147.933918 -90)
		(property "Reference" "X4"
			(at -1.809496 3.220974 0)
			(unlocked yes)
			(layer "F.SilkS")
			(effects
				(font
					(size 0.7874 0.5842)
					(thickness 0.1524)
				)
				(justify left)
			)
		)
		(property "Value" ""
			(at 0 0 270)
			(layer "F.Fab")
			(effects
				(font
					(size 1.27 1.27)
				)
			)
		)
		(property "Device Type" "TP_TDR_4P_FTS_TH-TP_TDR_4P_DIP,EMPTY,TP15"
			(at 1.30175 1.27 0)
			(unlocked yes)
			(layer "F.Fab")
			(hide yes)
			(effects
				(font
					(size 0.635 0.4064)
					(thickness 0.1524)
				)
			)
		)
		(property "User Part Number" "N_A"
			(at 1.30175 1.27 0)
			(unlocked yes)
			(layer "Cmts.User")
			(hide yes)
			(effects
				(font
					(size 0.635 0.4064)
					(thickness 0.1524)
				)
			)
		)
		(duplicate_pad_numbers_are_jumpers no)
		(fp_line
			(start 0 3.81)
			(end 2.54 3.81)
			(stroke
				(width 0.1524)
				(type default)
			)
			(layer "F.SilkS")
		)
		(fp_line
			(start 2.54 3.81)
			(end 2.54 3.6703)
			(stroke
				(width 0.1524)
				(type default)
			)
			(layer "F.SilkS")
		)
		(fp_line
			(start 0 3.175)
			(end 0 3.81)
			(stroke
				(width 0.1524)
				(type default)
			)
			(layer "F.SilkS")
		)
		(fp_line
			(start 2.54 1.4097)
			(end 2.54 1.1303)
			(stroke
				(width 0.1524)
				(type default)
			)
			(layer "F.SilkS")
		)
		(fp_line
			(start 0 0.635)
			(end 0 1.905)
			(stroke
				(width 0.1524)
				(type default)
			)
			(layer "F.SilkS")
		)
		(fp_line
			(start 2.54 -1.1303)
			(end 2.54 -1.27)
			(stroke
				(width 0.1524)
				(type default)
			)
			(layer "F.SilkS")
		)
		(fp_line
			(start 0 -1.27)
			(end 0 -0.635)
			(stroke
				(width 0.1524)
				(type default)
			)
			(layer "F.SilkS")
		)
		(fp_line
			(start 2.54 -1.27)
			(end 0 -1.27)
			(stroke
				(width 0.1524)
				(type default)
			)
			(layer "F.SilkS")
		)
		(fp_poly
			(pts
				(xy -0.761746 0) (xy -2.285746 0.762) (xy -2.285746 -0.762)
			)
			(stroke
				(width 0)
				(type default)
			)
			(fill yes)
			(layer "F.SilkS")
		)
		(fp_line
			(start 0 3.81)
			(end 2.54 3.81)
			(stroke
				(width 0.1)
				(type default)
			)
			(layer "F.Fab")
		)
		(fp_line
			(start 2.54 3.81)
			(end 2.54 -1.27)
			(stroke
				(width 0.1)
				(type default)
			)
			(layer "F.Fab")
		)
		(fp_line
			(start 0 -1.27)
			(end 0 3.81)
			(stroke
				(width 0.1)
				(type default)
			)
			(layer "F.Fab")
		)
		(fp_line
			(start 2.54 -1.27)
			(end 0 -1.27)
			(stroke
				(width 0.1)
				(type default)
			)
			(layer "F.Fab")
		)
		(fp_poly
			(pts
				(xy -0.761746 0) (xy -2.285746 -0.762) (xy -2.285746 0.762)
			)
			(stroke
				(width 0)
				(type default)
			)
			(fill yes)
			(layer "F.Fab")
		)
		(pad "1" thru_hole circle
			(at 0 0 270)
			(size 1.0033 1.0033)
			(drill 0.249936)
			(layers "*.Cu" "*.Mask")
			(remove_unused_layers no)
			(net "TDR_DIFF_80_IN3_DP")
			(clearance 0.10795)
			(thermal_gap 0.10795)
			(padstack
				(mode front_inner_back)
				(layer "Inner"
					(shape circle)
					(size 0.8001 0.8001)
					(clearance 0.1524)
				)
				(layer "B.Cu"
					(shape circle)
					(size 1.0033 1.0033)
					(clearance 0.10795)
				)
			)
		)
		(pad "2" thru_hole circle
			(at 2.54 0 270)
			(size 1.9939 1.9939)
			(drill 0.249936)
			(layers "*.Cu" "*.Mask")
			(remove_unused_layers no)
			(net "T1_GND")
			(clearance 0.10795)
			(thermal_gap 0.10795)
			(padstack
				(mode front_inner_back)
				(layer "Inner"
					(shape circle)
					(size 0.8001 0.8001)
					(clearance 0.1524)
				)
				(layer "B.Cu"
					(shape circle)
					(size 1.9939 1.9939)
					(clearance 0.10795)
				)
			)
		)
		(pad "3" thru_hole circle
			(at 2.54 2.54 270)
			(size 1.9939 1.9939)
			(drill 0.249936)
			(layers "*.Cu" "*.Mask")
			(remove_unused_layers no)
			(net "T1_GND")
			(clearance 0.10795)
			(thermal_gap 0.10795)
			(padstack
				(mode front_inner_back)
				(layer "Inner"
					(shape circle)
					(size 0.8001 0.8001)
					(clearance 0.1524)
				)
				(layer "B.Cu"
					(shape circle)
					(size 1.9939 1.9939)
					(clearance 0.10795)
				)
			)
		)
		(pad "4" thru_hole circle
			(at 0 2.54 270)
			(size 1.0033 1.0033)
			(drill 0.249936)
			(layers "*.Cu" "*.Mask")
			(remove_unused_layers no)
			(net "TDR_DIFF_80_IN3_DN")
			(clearance 0.10795)
			(thermal_gap 0.10795)
			(padstack
				(mode front_inner_back)
				(layer "Inner"
					(shape circle)
					(size 0.8001 0.8001)
					(clearance 0.1524)
				)
				(layer "B.Cu"
					(shape circle)
					(size 1.0033 1.0033)
					(clearance 0.10795)
				)
			)
		)
	)
)
